# T6G (Grand Teton) — schematic netlist excerpt (pin names and nets, part order shuffled) for the footprints in the layout excerpt that follows; sources: Cadence DE-HDL packaged netlist, KiCad conversion of 04192023_DAF0TMB3IC0_F0TG_MB_C_brd_V02_OCP.brd

R560  Q_RES  10K 1% CHIP  pkg 0402LF  page 183 : A = P3V3_AUX ; B = FM_9ZXL045_P1_DEV_EN

U6006  APX80929SAG7  APX809-29SAG-7 IC  pkg SOT23_123XI  page 188
  GND  = GND
  RESET_L  = PWRGD_P3V3_EN_R
  VCC  = P3V3

R6055  Q_RES  0 5% CHIP  pkg 0402LF  page 81 : A = HP_LVC3_SCM_HSC_PWRGD ; B = P12V_SCM_PWRGD_R

(kicad_pcb
	(version 20260206)
	(generator "pcbnew")
	(generator_version "10.0")
	(general
		(thickness 1.6)
		(legacy_teardrops no)
	)
	(paper "A4")
	(title_block
		(title "04192023_DAF0TMB3IC0_F0TG_MB_C_brd_V02_OCP.brd")
		(comment 1 "Grand Teton / footprints 4203-4205 of 8354")
	)
	(layers
		(0 "F.Cu" signal "TOP")
		(4 "In1.Cu" signal "GND")
		(6 "In2.Cu" signal "IN1")
		(8 "In3.Cu" signal "GND1")
		(10 "In4.Cu" signal "IN2")
		(12 "In5.Cu" signal "GND2")
		(14 "In6.Cu" signal "IN3")
		(16 "In7.Cu" signal "GND3")
		(18 "In8.Cu" signal "VCC")
		(20 "In9.Cu" signal "VCC1")
		(22 "In10.Cu" signal "GND4")
		(24 "In11.Cu" signal "IN4")
		(26 "In12.Cu" signal "GND5")
		(28 "In13.Cu" signal "IN5")
		(30 "In14.Cu" signal "GND6")
		(32 "In15.Cu" signal "IN6")
		(34 "In16.Cu" signal "GND7")
		(2 "B.Cu" signal "BOTTOM")
		(9 "F.Adhes" user "F.Adhesive")
		(11 "B.Adhes" user "B.Adhesive")
		(13 "F.Paste" user "Package Geometry/Pastemask Top")
		(15 "B.Paste" user "Package Geometry/Pastemask Bottom")
		(5 "F.SilkS" user "Ref Des/Silkscreen Top")
		(7 "B.SilkS" user "Ref Des/Silkscreen Bottom")
		(1 "F.Mask" user "Board Geometry/Soldermask Top")
		(3 "B.Mask" user "Board Geometry/Soldermask Bottom")
		(17 "Dwgs.User" user "User.Drawings")
		(19 "Cmts.User" user "User.Comments")
		(21 "Eco1.User" user "User.Eco1")
		(23 "Eco2.User" user "User.Eco2")
		(25 "Edge.Cuts" user "Board Geometry/Outline")
		(27 "Margin" user)
		(31 "F.CrtYd" user "Package Geometry/Place Bound Top")
		(29 "B.CrtYd" user "Package Geometry/Place Bound Bottom")
		(35 "F.Fab" user "Ref Des/Assembly Top")
		(33 "B.Fab" user "Ref Des/Assembly Bottom")
	)
	(footprint ""
		(layer "F.Cu")
		(at 116.332 -125.349)
		(property "Reference" "U6006"
			(at -1.979676 -2.710942 0)
			(unlocked yes)
			(layer "F.SilkS")
			(effects
				(font
					(size 0.7874 0.5842)
					(thickness 0.1524)
				)
				(justify left)
			)
		)
		(property "Value" ""
			(at 0 0 0)
			(layer "F.Fab")
			(effects
				(font
					(size 1.27 1.27)
				)
			)
		)
		(duplicate_pad_numbers_are_jumpers no)
		(fp_line
			(start -1.759712 -1.500124)
			(end 1.759712 -1.500124)
			(stroke
				(width 0.1524)
				(type default)
			)
			(layer "F.SilkS")
		)
		(fp_line
			(start -1.759712 1.500124)
			(end -1.759712 -1.500124)
			(stroke
				(width 0.1524)
				(type default)
			)
			(layer "F.SilkS")
		)
		(fp_line
			(start 1.759712 -1.500124)
			(end 1.759712 1.500124)
			(stroke
				(width 0.1524)
				(type default)
			)
			(layer "F.SilkS")
		)
		(fp_line
			(start 1.759712 1.500124)
			(end -1.759712 1.500124)
			(stroke
				(width 0.1524)
				(type default)
			)
			(layer "F.SilkS")
		)
		(fp_line
			(start -0.700024 -1.500124)
			(end 0.700024 -1.500124)
			(stroke
				(width 0.1)
				(type default)
			)
			(layer "F.Fab")
		)
		(fp_line
			(start -0.700024 1.500124)
			(end -0.700024 -1.500124)
			(stroke
				(width 0.1)
				(type default)
			)
			(layer "F.Fab")
		)
		(fp_line
			(start 0.700024 -1.500124)
			(end 0.700024 1.500124)
			(stroke
				(width 0.1)
				(type default)
			)
			(layer "F.Fab")
		)
		(fp_line
			(start 0.700024 1.500124)
			(end -0.700024 1.500124)
			(stroke
				(width 0.1)
				(type default)
			)
			(layer "F.Fab")
		)
		(pad "1" smd rect
			(at -1.150112 -0.94996 270)
			(size 0.6604 0.9652)
			(layers "F.Cu" "F.Mask" "F.Paste")
			(net "GND")
		)
		(pad "2" smd rect
			(at -1.150112 0.94996 270)
			(size 0.6604 0.9652)
			(layers "F.Cu" "F.Mask" "F.Paste")
			(net "PWRGD_P3V3_EN_R")
		)
		(pad "3" smd rect
			(at 1.150112 0 270)
			(size 0.6604 0.9652)
			(layers "F.Cu" "F.Mask" "F.Paste")
			(net "P3V3")
		)
	)
	(footprint ""
		(layer "F.Cu")
		(at 208.894426 -109.561376 180)
		(property "Reference" "R6055"
			(at 0 0 180)
			(layer "F.SilkS")
			(hide yes)
			(effects
				(font
					(size 1.27 1.27)
				)
			)
		)
		(property "Value" ""
			(at 0 0 180)
			(layer "F.Fab")
			(effects
				(font
					(size 1.27 1.27)
				)
			)
		)
		(duplicate_pad_numbers_are_jumpers no)
		(fp_line
			(start 0.7874 0.4064)
			(end -0.7874 0.4064)
			(stroke
				(width 0.1524)
				(type default)
			)
			(layer "F.SilkS")
		)
		(fp_line
			(start 0.7874 -0.4064)
			(end 0.7874 0.4064)
			(stroke
				(width 0.1524)
				(type default)
			)
			(layer "F.SilkS")
		)
		(fp_line
			(start -0.7874 0.4064)
			(end -0.7874 -0.4064)
			(stroke
				(width 0.1524)
				(type default)
			)
			(layer "F.SilkS")
		)
		(fp_line
			(start -0.7874 -0.4064)
			(end 0.7874 -0.4064)
			(stroke
				(width 0.1524)
				(type default)
			)
			(layer "F.SilkS")
		)
		(fp_line
			(start 0.67945 0.3048)
			(end 0.120396 0.3048)
			(stroke
				(width 0.1)
				(type default)
			)
			(layer "F.Fab")
		)
		(fp_line
			(start 0.67945 -0.3048)
			(end 0.67945 0.3048)
			(stroke
				(width 0.1)
				(type default)
			)
			(layer "F.Fab")
		)
		(fp_line
			(start 0.12065 -0.2794)
			(end 0.12065 -0.3048)
			(stroke
				(width 0.1)
				(type default)
			)
			(layer "F.Fab")
		)
		(fp_line
			(start 0.12065 -0.3048)
			(end 0.67945 -0.3048)
			(stroke
				(width 0.1)
				(type default)
			)
			(layer "F.Fab")
		)
		(fp_line
			(start 0.120396 0.3048)
			(end 0.120396 0.2794)
			(stroke
				(width 0.1)
				(type default)
			)
			(layer "F.Fab")
		)
		(fp_line
			(start 0.120396 0.2794)
			(end -0.12065 0.2794)
			(stroke
				(width 0.1)
				(type default)
			)
			(layer "F.Fab")
		)
		(fp_line
			(start -0.12065 0.3048)
			(end -0.67945 0.3048)
			(stroke
				(width 0.1)
				(type default)
			)
			(layer "F.Fab")
		)
		(fp_line
			(start -0.12065 0.2794)
			(end -0.12065 0.3048)
			(stroke
				(width 0.1)
				(type default)
			)
			(layer "F.Fab")
		)
		(fp_line
			(start -0.12065 -0.2794)
			(end 0.12065 -0.2794)
			(stroke
				(width 0.1)
				(type default)
			)
			(layer "F.Fab")
		)
		(fp_line
			(start -0.12065 -0.305054)
			(end -0.12065 -0.2794)
			(stroke
				(width 0.1)
				(type default)
			)
			(layer "F.Fab")
		)
		(fp_line
			(start -0.67945 0.3048)
			(end -0.67945 -0.305054)
			(stroke
				(width 0.1)
				(type default)
			)
			(layer "F.Fab")
		)
		(fp_line
			(start -0.67945 -0.305054)
			(end -0.12065 -0.305054)
			(stroke
				(width 0.1)
				(type default)
			)
			(layer "F.Fab")
		)
		(pad "1" smd circle
			(at -0.40005 0 180)
			(size 0 0)
			(layers "F.Cu" "F.Mask" "F.Paste")
			(net "HP_LVC3_SCM_HSC_PWRGD")
		)
		(pad "2" smd circle
			(at 0.40005 0 180)
			(size 0 0)
			(layers "F.Cu" "F.Mask" "F.Paste")
			(net "P12V_SCM_PWRGD_R")
		)
	)
	(footprint ""
		(layer "F.Cu")
		(at 108.839 -415.417 -90)
		(property "Reference" "R560"
			(at 0 0 270)
			(layer "F.SilkS")
			(hide yes)
			(effects
				(font
					(size 1.27 1.27)
				)
			)
		)
		(property "Value" ""
			(at 0 0 270)
			(layer "F.Fab")
			(effects
				(font
					(size 1.27 1.27)
				)
			)
		)
		(duplicate_pad_numbers_are_jumpers no)
		(fp_line
			(start -0.7874 0.4064)
			(end -0.7874 -0.4064)
			(stroke
				(width 0.1524)
				(type default)
			)
			(layer "F.SilkS")
		)
		(fp_line
			(start 0.7874 0.4064)
			(end -0.7874 0.4064)
			(stroke
				(width 0.1524)
				(type default)
			)
			(layer "F.SilkS")
		)
		(fp_line
			(start -0.7874 -0.4064)
			(end 0.7874 -0.4064)
			(stroke
				(width 0.1524)
				(type default)
			)
			(layer "F.SilkS")
		)
		(fp_line
			(start 0.7874 -0.4064)
			(end 0.7874 0.4064)
			(stroke
				(width 0.1524)
				(type default)
			)
			(layer "F.SilkS")
		)
		(fp_line
			(start -0.67945 0.3048)
			(end -0.67945 -0.305054)
			(stroke
				(width 0.1)
				(type default)
			)
			(layer "F.Fab")
		)
		(fp_line
			(start -0.12065 0.3048)
			(end -0.67945 0.3048)
			(stroke
				(width 0.1)
				(type default)
			)
			(layer "F.Fab")
		)
		(fp_line
			(start 0.120396 0.3048)
			(end 0.120396 0.2794)
			(stroke
				(width 0.1)
				(type default)
			)
			(layer "F.Fab")
		)
		(fp_line
			(start 0.67945 0.3048)
			(end 0.120396 0.3048)
			(stroke
				(width 0.1)
				(type default)
			)
			(layer "F.Fab")
		)
		(fp_line
			(start -0.12065 0.2794)
			(end -0.12065 0.3048)
			(stroke
				(width 0.1)
				(type default)
			)
			(layer "F.Fab")
		)
		(fp_line
			(start 0.120396 0.2794)
			(end -0.12065 0.2794)
			(stroke
				(width 0.1)
				(type default)
			)
			(layer "F.Fab")
		)
		(fp_line
			(start -0.12065 -0.2794)
			(end 0.12065 -0.2794)
			(stroke
				(width 0.1)
				(type default)
			)
			(layer "F.Fab")
		)
		(fp_line
			(start 0.12065 -0.2794)
			(end 0.12065 -0.3048)
			(stroke
				(width 0.1)
				(type default)
			)
			(layer "F.Fab")
		)
		(fp_line
			(start 0.12065 -0.3048)
			(end 0.67945 -0.3048)
			(stroke
				(width 0.1)
				(type default)
			)
			(layer "F.Fab")
		)
		(fp_line
			(start 0.67945 -0.3048)
			(end 0.67945 0.3048)
			(stroke
				(width 0.1)
				(type default)
			)
			(layer "F.Fab")
		)
		(fp_line
			(start -0.67945 -0.305054)
			(end -0.12065 -0.305054)
			(stroke
				(width 0.1)
				(type default)
			)
			(layer "F.Fab")
		)
		(fp_line
			(start -0.12065 -0.305054)
			(end -0.12065 -0.2794)
			(stroke
				(width 0.1)
				(type default)
			)
			(layer "F.Fab")
		)
		(pad "1" smd circle
			(at -0.40005 0 270)
			(size 0 0)
			(layers "F.Cu" "F.Mask" "F.Paste")
			(net "P3V3_AUX")
		)
		(pad "2" smd circle
			(at 0.40005 0 270)
			(size 0 0)
			(layers "F.Cu" "F.Mask" "F.Paste")
			(net "FM_9ZXL045_P1_DEV_EN")
		)
	)
)
